(kicad_pcb
	(version 20260206)
	(generator "pcbnew")
	(generator_version "10.0")
	(general
		(thickness 1.6)
		(legacy_teardrops no)
	)
	(paper "A4")
	(title_block
		(title "Wiwynn_Tioga_Pass_MB.brd")
		(comment 1 "Tioga Pass / footprint 4543 of 4770 (J9U2), pads 244-291 of 291")
	)
	(layers
		(0 "F.Cu" signal "TOP")
		(4 "In1.Cu" signal "L2GND")
		(6 "In2.Cu" signal "L3")
		(8 "In3.Cu" signal "L4GND")
		(10 "In4.Cu" signal "L5")
		(12 "In5.Cu" signal "L6GND")
		(14 "In6.Cu" signal "L7VCC")
		(16 "In7.Cu" signal "L8VCC")
		(18 "In8.Cu" signal "L9GND")
		(20 "In9.Cu" signal "L10")
		(22 "In10.Cu" signal "L11GND")
		(24 "In11.Cu" signal "L12")
		(26 "In12.Cu" signal "L13GND")
		(2 "B.Cu" signal "BOTTOM")
		(9 "F.Adhes" user "F.Adhesive")
		(11 "B.Adhes" user "B.Adhesive")
		(13 "F.Paste" user "Package Geometry/Pastemask Top")
		(15 "B.Paste" user "Package Geometry/Pastemask Bottom")
		(5 "F.SilkS" user "Ref Des/Silkscreen Top")
		(7 "B.SilkS" user "Ref Des/Silkscreen Bottom")
		(1 "F.Mask" user "Board Geometry/Soldermask Top")
		(3 "B.Mask" user "Board Geometry/Soldermask Bottom")
		(17 "Dwgs.User" user "User.Drawings")
		(19 "Cmts.User" user "User.Comments")
		(21 "Eco1.User" user "User.Eco1")
		(23 "Eco2.User" user "User.Eco2")
		(25 "Edge.Cuts" user "Board Geometry/Outline")
		(27 "Margin" user)
		(31 "F.CrtYd" user "Package Geometry/Place Bound Top")
		(29 "B.CrtYd" user "Package Geometry/Place Bound Bottom")
		(35 "F.Fab" user "Ref Des/Assembly Top")
		(33 "B.Fab" user "Ref Des/Assembly Bottom")
	)
	(footprint ""
		(layer "B.Cu")
		(at 29.699458 -5.621782 90)
		(property "Reference" "J9U2"
			(at 2.098548 38.118542 0)
			(unlocked yes)
			(layer "B.SilkS")
			(effects
				(font
					(size 0.7874 0.5842)
					(thickness 0.1524)
				)
				(justify left mirror)
			)
		)
		(property "Value" ""
			(at 0 0 90)
			(layer "B.Fab")
			(effects
				(font
					(size 1.27 1.27)
				)
				(justify mirror)
			)
		)
		(duplicate_pad_numbers_are_jumpers no)
		(pad "241" smd rect
			(at -4.59994 86.700106 270)
			(size 1.8034 0.508)
			(layers "B.Cu" "B.Mask" "B.Paste")
			(net "GND")
		)
		(pad "242" smd rect
			(at -4.59994 87.54999 270)
			(size 1.8034 0.508)
			(layers "B.Cu" "B.Mask" "B.Paste")
			(net "M_J_DQ<33>")
		)
		(pad "243" smd rect
			(at -4.59994 88.399874 270)
			(size 1.8034 0.508)
			(layers "B.Cu" "B.Mask" "B.Paste")
			(net "GND")
		)
		(pad "244" smd rect
			(at -4.59994 89.250012 270)
			(size 1.8034 0.508)
			(layers "B.Cu" "B.Mask" "B.Paste")
			(net "M_J_DQS_DN<4>")
		)
		(pad "245" smd rect
			(at -4.59994 90.099896 270)
			(size 1.8034 0.508)
			(layers "B.Cu" "B.Mask" "B.Paste")
			(net "M_J_DQS_DP<4>")
		)
		(pad "246" smd rect
			(at -4.59994 90.950034 270)
			(size 1.8034 0.508)
			(layers "B.Cu" "B.Mask" "B.Paste")
			(net "GND")
		)
		(pad "247" smd rect
			(at -4.59994 91.799918 270)
			(size 1.8034 0.508)
			(layers "B.Cu" "B.Mask" "B.Paste")
			(net "M_J_DQ<39>")
		)
		(pad "248" smd rect
			(at -4.59994 92.650056 270)
			(size 1.8034 0.508)
			(layers "B.Cu" "B.Mask" "B.Paste")
			(net "GND")
		)
		(pad "249" smd rect
			(at -4.59994 93.49994 270)
			(size 1.8034 0.508)
			(layers "B.Cu" "B.Mask" "B.Paste")
			(net "M_J_DQ<35>")
		)
		(pad "250" smd rect
			(at -4.59994 94.350078 270)
			(size 1.8034 0.508)
			(layers "B.Cu" "B.Mask" "B.Paste")
			(net "GND")
		)
		(pad "251" smd rect
			(at -4.59994 95.199962 270)
			(size 1.8034 0.508)
			(layers "B.Cu" "B.Mask" "B.Paste")
			(net "M_J_DQ<45>")
		)
		(pad "252" smd rect
			(at -4.59994 96.0501 270)
			(size 1.8034 0.508)
			(layers "B.Cu" "B.Mask" "B.Paste")
			(net "GND")
		)
		(pad "253" smd rect
			(at -4.59994 96.899984 270)
			(size 1.8034 0.508)
			(layers "B.Cu" "B.Mask" "B.Paste")
			(net "M_J_DQ<41>")
		)
		(pad "254" smd rect
			(at -4.59994 97.750122 270)
			(size 1.8034 0.508)
			(layers "B.Cu" "B.Mask" "B.Paste")
			(net "GND")
		)
		(pad "255" smd rect
			(at -4.59994 98.600006 270)
			(size 1.8034 0.508)
			(layers "B.Cu" "B.Mask" "B.Paste")
			(net "M_J_DQS_DN<5>")
		)
		(pad "256" smd rect
			(at -4.59994 99.44989 270)
			(size 1.8034 0.508)
			(layers "B.Cu" "B.Mask" "B.Paste")
			(net "M_J_DQS_DP<5>")
		)
		(pad "257" smd rect
			(at -4.59994 100.300028 270)
			(size 1.8034 0.508)
			(layers "B.Cu" "B.Mask" "B.Paste")
			(net "GND")
		)
		(pad "258" smd rect
			(at -4.59994 101.149912 270)
			(size 1.8034 0.508)
			(layers "B.Cu" "B.Mask" "B.Paste")
			(net "M_J_DQ<47>")
		)
		(pad "259" smd rect
			(at -4.59994 102.00005 270)
			(size 1.8034 0.508)
			(layers "B.Cu" "B.Mask" "B.Paste")
			(net "GND")
		)
		(pad "260" smd rect
			(at -4.59994 102.849934 270)
			(size 1.8034 0.508)
			(layers "B.Cu" "B.Mask" "B.Paste")
			(net "M_J_DQ<43>")
		)
		(pad "261" smd rect
			(at -4.59994 103.700072 270)
			(size 1.8034 0.508)
			(layers "B.Cu" "B.Mask" "B.Paste")
			(net "GND")
		)
		(pad "262" smd rect
			(at -4.59994 104.549956 270)
			(size 1.8034 0.508)
			(layers "B.Cu" "B.Mask" "B.Paste")
			(net "M_J_DQ<53>")
		)
		(pad "263" smd rect
			(at -4.59994 105.400094 270)
			(size 1.8034 0.508)
			(layers "B.Cu" "B.Mask" "B.Paste")
			(net "GND")
		)
		(pad "264" smd rect
			(at -4.59994 106.249978 270)
			(size 1.8034 0.508)
			(layers "B.Cu" "B.Mask" "B.Paste")
			(net "M_J_DQ<49>")
		)
		(pad "265" smd rect
			(at -4.59994 107.100116 270)
			(size 1.8034 0.508)
			(layers "B.Cu" "B.Mask" "B.Paste")
			(net "GND")
		)
		(pad "266" smd rect
			(at -4.59994 107.95 270)
			(size 1.8034 0.508)
			(layers "B.Cu" "B.Mask" "B.Paste")
			(net "M_J_DQS_DN<6>")
		)
		(pad "267" smd rect
			(at -4.59994 108.799884 270)
			(size 1.8034 0.508)
			(layers "B.Cu" "B.Mask" "B.Paste")
			(net "M_J_DQS_DP<6>")
		)
		(pad "268" smd rect
			(at -4.59994 109.650022 270)
			(size 1.8034 0.508)
			(layers "B.Cu" "B.Mask" "B.Paste")
			(net "GND")
		)
		(pad "269" smd rect
			(at -4.59994 110.499906 270)
			(size 1.8034 0.508)
			(layers "B.Cu" "B.Mask" "B.Paste")
			(net "M_J_DQ<55>")
		)
		(pad "270" smd rect
			(at -4.59994 111.350044 270)
			(size 1.8034 0.508)
			(layers "B.Cu" "B.Mask" "B.Paste")
			(net "GND")
		)
		(pad "271" smd rect
			(at -4.59994 112.199928 270)
			(size 1.8034 0.508)
			(layers "B.Cu" "B.Mask" "B.Paste")
			(net "M_J_DQ<51>")
		)
		(pad "272" smd rect
			(at -4.59994 113.050066 270)
			(size 1.8034 0.508)
			(layers "B.Cu" "B.Mask" "B.Paste")
			(net "GND")
		)
		(pad "273" smd rect
			(at -4.59994 113.89995 270)
			(size 1.8034 0.508)
			(layers "B.Cu" "B.Mask" "B.Paste")
			(net "M_J_DQ<61>")
		)
		(pad "274" smd rect
			(at -4.59994 114.750088 270)
			(size 1.8034 0.508)
			(layers "B.Cu" "B.Mask" "B.Paste")
			(net "GND")
		)
		(pad "275" smd rect
			(at -4.59994 115.599972 270)
			(size 1.8034 0.508)
			(layers "B.Cu" "B.Mask" "B.Paste")
			(net "M_J_DQ<57>")
		)
		(pad "276" smd rect
			(at -4.59994 116.45011 270)
			(size 1.8034 0.508)
			(layers "B.Cu" "B.Mask" "B.Paste")
			(net "GND")
		)
		(pad "277" smd rect
			(at -4.59994 117.299994 270)
			(size 1.8034 0.508)
			(layers "B.Cu" "B.Mask" "B.Paste")
			(net "M_J_DQS_DN<7>")
		)
		(pad "278" smd rect
			(at -4.59994 118.149878 270)
			(size 1.8034 0.508)
			(layers "B.Cu" "B.Mask" "B.Paste")
			(net "M_J_DQS_DP<7>")
		)
		(pad "279" smd rect
			(at -4.59994 119.000016 270)
			(size 1.8034 0.508)
			(layers "B.Cu" "B.Mask" "B.Paste")
			(net "GND")
		)
		(pad "280" smd rect
			(at -4.59994 119.8499 270)
			(size 1.8034 0.508)
			(layers "B.Cu" "B.Mask" "B.Paste")
			(net "M_J_DQ<63>")
		)
		(pad "281" smd rect
			(at -4.59994 120.700038 270)
			(size 1.8034 0.508)
			(layers "B.Cu" "B.Mask" "B.Paste")
			(net "GND")
		)
		(pad "282" smd rect
			(at -4.59994 121.549922 270)
			(size 1.8034 0.508)
			(layers "B.Cu" "B.Mask" "B.Paste")
			(net "M_J_DQ<59>")
		)
		(pad "283" smd rect
			(at -4.59994 122.40006 270)
			(size 1.8034 0.508)
			(layers "B.Cu" "B.Mask" "B.Paste")
			(net "GND")
		)
		(pad "284" smd rect
			(at -4.59994 123.249944 270)
			(size 1.8034 0.508)
			(layers "B.Cu" "B.Mask" "B.Paste")
			(net "PVPP_GHJ")
		)
		(pad "285" smd rect
			(at -4.59994 124.100082 270)
			(size 1.8034 0.508)
			(layers "B.Cu" "B.Mask" "B.Paste")
			(net "SMB_DDR_GHJ_VPP_SDA")
		)
		(pad "286" smd rect
			(at -4.59994 124.949966 270)
			(size 1.8034 0.508)
			(layers "B.Cu" "B.Mask" "B.Paste")
			(net "PVPP_GHJ")
		)
		(pad "287" smd rect
			(at -4.59994 125.800104 270)
			(size 1.8034 0.508)
			(layers "B.Cu" "B.Mask" "B.Paste")
			(net "PVPP_GHJ")
		)
		(pad "288" smd rect
			(at -4.59994 126.649988 270)
			(size 1.8034 0.508)
			(layers "B.Cu" "B.Mask" "B.Paste")
			(net "PVPP_GHJ")
		)
	)
)
